# BASEBOARD_FAB2 (Tioga Pass) — schematic netlist excerpt (pin names and nets, part order shuffled) for the footprints in the layout excerpt that follows; sources: Cadence DE-HDL packaged netlist, KiCad conversion of Wiwynn_Tioga_Pass_MB.brd

J1G2  SCONN288_H44441004  SCONN  pkg PIP  page 79
  \12v\(1)  = P12V_NVDIMM_GHJ
  VSS(93)  = GND
  DQ(4)  = M_H_DQ<5>
  VSS(92)  = GND
  DQ(0)  = M_H_DQ<1>
  VSS(91)  = GND
  DQS9P  = M_H_DQS_DP<9>
  DQS9N  = M_H_DQS_DN<9>
  VSS(90)  = GND
  DQ(6)  = M_H_DQ<7>
  VSS(89)  = GND
  DQ(2)  = M_H_DQ<3>
  VSS(88)  = GND
  DQ(12)  = M_H_DQ<13>
  VSS(87)  = GND
  DQ(8)  = M_H_DQ<9>
  VSS(86)  = GND
  DQS10P  = M_H_DQS_DP<10>
  DQS10N  = M_H_DQS_DN<10>
  VSS(85)  = GND
  DQ(14)  = M_H_DQ<15>
  VSS(84)  = GND
  DQ(10)  = M_H_DQ<11>
  VSS(83)  = GND
  DQ(20)  = M_H_DQ<21>
  VSS(82)  = GND
  DQ(16)  = M_H_DQ<17>
  VSS(81)  = GND
  DQS11P  = M_H_DQS_DP<11>
  DQS11N  = M_H_DQS_DN<11>
  VSS(80)  = GND
  DQ(22)  = M_H_DQ<23>
  VSS(79)  = GND
  DQ(18)  = M_H_DQ<19>
  VSS(78)  = GND
  DQ(28)  = M_H_DQ<29>
  VSS(77)  = GND
  DQ(24)  = M_H_DQ<25>
  VSS(76)  = GND
  DQS12P  = M_H_DQS_DP<12>
  DQS12N  = M_H_DQS_DN<12>
  VSS(75)  = GND
  DQ(30)  = M_H_DQ<31>
  VSS(74)  = GND
  DQ(26)  = M_H_DQ<27>
  VSS(73)  = GND
  CB(4)  = M_H_ECC<5>
  VSS(72)  = GND
  CB(0)  = M_H_ECC<1>
  VSS(71)  = GND
  DQS17P  = M_H_DQS_DP<17>
  DQS17N  = M_H_DQS_DN<17>
  VSS(70)  = GND
  CB(6)  = M_H_ECC<7>
  VSS(69)  = GND
  CB(2)  = M_H_ECC<3>
  VSS(68)  = GND
  RESET_N  = M_GHJ_RST_N
  VDD(25)  = PVDDQ_GHJ
  CKE(0)  = M_H_CKE<0>
  VDD(24)  = PVDDQ_GHJ
  ACT_N  = M_H_ACT_N
  BG(0)  = M_H_BG<0>
  VDD(23)  = PVDDQ_GHJ
  A12  = M_H_MA<12>
  A9  = M_H_MA<9>
  VDD(22)  = PVDDQ_GHJ
  A8  = M_H_MA<8>
  A6  = M_H_MA<6>
  VDD(21)  = PVDDQ_GHJ
  A3  = M_H_MA<3>
  A1  = M_H_MA<1>
  VDD(20)  = PVDDQ_GHJ
  CK0P  = M_H_CLK_DP<0>
  CK0N  = M_H_CLK_DN<0>
  VDD(19)  = PVDDQ_GHJ
  VTT(1)  = PVTT_GHJ
  EVENT_N  = FM_DIMM_EVENT_COD_N
  A0  = M_H_MA<0>
  VDD(18)  = PVDDQ_GHJ
  BA(0)  = M_H_BA<0>
  A16_RAS_N  = M_H_MA<16>
  VDD(17)  = PVDDQ_GHJ
  S0_N  = M_H_CS_N<0>
  VDD(16)  = PVDDQ_GHJ
  A15_CAS_N  = M_H_MA<15>
  ODT(0)  = M_H_ODT<0>
  VDD(15)  = PVDDQ_GHJ
  S1_N  = M_H_CS_N<1>
  VDD(14)  = PVDDQ_GHJ
  ODT(1)  = M_H_ODT<1>
  VDD(13)  = PVDDQ_GHJ
  S2_N_C(0)  = M_H_CS_N<2>
  VSS(67)  = GND
  DQ(36)  = M_H_DQ<37>
  VSS(66)  = GND
  DQ(32)  = M_H_DQ<33>
  VSS(65)  = GND
  DQS13P  = M_H_DQS_DP<13>
  DQS13N  = M_H_DQS_DN<13>
  VSS(64)  = GND
  DQ(38)  = M_H_DQ<39>
  VSS(63)  = GND
  DQ(34)  = M_H_DQ<35>
  VSS(62)  = GND
  DQ(44)  = M_H_DQ<45>
  VSS(61)  = GND
  DQ(40)  = M_H_DQ<41>
  VSS(60)  = GND
  DQS14P  = M_H_DQS_DP<14>
  DQS14N  = M_H_DQS_DN<14>
  VSS(59)  = GND
  DQ(46)  = M_H_DQ<47>
  VSS(58)  = GND
  DQ(42)  = M_H_DQ<43>
  VSS(57)  = GND
  DQ(52)  = M_H_DQ<53>
  VSS(56)  = GND
  DQ(48)  = M_H_DQ<49>
  VSS(55)  = GND
  DQS15P  = M_H_DQS_DP<15>
  DQS15N  = M_H_DQS_DN<15>
  VSS(54)  = GND
  DQ(54)  = M_H_DQ<55>
  VSS(53)  = GND
  DQ(50)  = M_H_DQ<51>
  VSS(52)  = GND
  DQ(60)  = M_H_DQ<61>
  VSS(51)  = GND
  DQ(56)  = M_H_DQ<57>
  VSS(50)  = GND
  DQS16P  = M_H_DQS_DP<16>
  DQS16N  = M_H_DQS_DN<16>
  VSS(49)  = GND
  DQ(62)  = M_H_DQ<63>
  VSS(48)  = GND
  DQ(58)  = M_H_DQ<59>
  VSS(47)  = GND
  SA(0)  = GND
  SA(1)  = PVPP_GHJ
  SCL  = SMB_DDR_GHJ_VPP_SCL
  VPP(4)  = PVPP_GHJ
  VPP(3)  = PVPP_GHJ
  RFU(2)  = TP_CH_H_DIMM_H0_RFU_2
  \12v\(0)  = P12V_NVDIMM_GHJ
  VREFCA  = M_H_VREF
  VSS(46)  = GND
  DQ(5)  = M_H_DQ<4>
  VSS(45)  = GND
  DQ(1)  = M_H_DQ<0>
  VSS(44)  = GND
  DQS0N  = M_H_DQS_DN<0>
  DQS0P  = M_H_DQS_DP<0>
  VSS(43)  = GND
  DQ(7)  = M_H_DQ<6>
  VSS(42)  = GND
  DQ(3)  = M_H_DQ<2>
  VSS(41)  = GND
  DQ(13)  = M_H_DQ<12>
  VSS(40)  = GND
  DQ(9)  = M_H_DQ<8>
  VSS(39)  = GND
  DQS1N  = M_H_DQS_DN<1>
  DQS1P  = M_H_DQS_DP<1>
  VSS(38)  = GND
  DQ(15)  = M_H_DQ<14>
  VSS(37)  = GND
  DQ(11)  = M_H_DQ<10>
  VSS(36)  = GND
  DQ(21)  = M_H_DQ<20>
  VSS(35)  = GND
  DQ(17)  = M_H_DQ<16>
  VSS(34)  = GND
  DQS2N  = M_H_DQS_DN<2>
  DQS2P  = M_H_DQS_DP<2>
  VSS(33)  = GND
  DQ(23)  = M_H_DQ<22>
  VSS(32)  = GND
  DQ(19)  = M_H_DQ<18>
  VSS(31)  = GND
  DQ(29)  = M_H_DQ<28>
  VSS(30)  = GND
  DQ(25)  = M_H_DQ<24>
  VSS(29)  = GND
  DQS3N  = M_H_DQS_DN<3>
  DQS3P  = M_H_DQS_DP<3>
  VSS(28)  = GND
  DQ(31)  = M_H_DQ<30>
  VSS(27)  = GND
  DQ(27)  = M_H_DQ<26>
  VSS(26)  = GND
  CB(5)  = M_H_ECC<4>
  VSS(25)  = GND
  CB(1)  = M_H_ECC<0>
  VSS(24)  = GND
  DQS8N  = M_H_DQS_DN<8>
  DQS8P  = M_H_DQS_DP<8>
  VSS(23)  = GND
  CB(7)  = M_H_ECC<6>
  VSS(22)  = GND
  CB(3)  = M_H_ECC<2>
  VSS(21)  = GND
  CKE(1)  = M_H_CKE<1>
  VDD(12)  = PVDDQ_GHJ
  RFU(0)  = TP_CH_H_DIMM_H0_RFU_0
  VDD(11)  = PVDDQ_GHJ
  BG(1)  = M_H_BG<1>
  ALERT_N  = M_H_ALERT_N
  VDD(10)  = PVDDQ_GHJ
  A11  = M_H_MA<11>
  A7  = M_H_MA<7>
  VDD(9)  = PVDDQ_GHJ
  A5  = M_H_MA<5>
  A4  = M_H_MA<4>
  VDD(8)  = PVDDQ_GHJ
  A2  = M_H_MA<2>
  VDD(7)  = PVDDQ_GHJ
  CK1P  = M_H_CLK_DP<1>
  CK1N  = M_H_CLK_DN<1>
  VDD(6)  = PVDDQ_GHJ
  VTT(0)  = PVTT_GHJ
  PAR  = M_H_PAR
  VDD(5)  = PVDDQ_GHJ
  BA(1)  = M_H_BA<1>
  A10  = M_H_MA<10>
  VDD(4)  = PVDDQ_GHJ
  RFU(1)  = TP_CH_H_DIMM_H0_RFU_1
  A14_WE_N  = M_H_MA<14>
  VDD(3)  = PVDDQ_GHJ
  SAVE_N_NC  = FM_ADR_COMPLETE_GHJ_N
  VDD(2)  = PVDDQ_GHJ
  A13  = M_H_MA<13>
  VDD(1)  = PVDDQ_GHJ
  A17  = M_H_MA<17>
  C(2)  = M_H_C<2>
  VDD(0)  = PVDDQ_GHJ
  S3_N_C(1)  = M_H_CS_N<3>
  SA(2)  = GND
  VSS(20)  = GND
  DQ(37)  = M_H_DQ<36>
  VSS(19)  = GND
  DQ(33)  = M_H_DQ<32>
  VSS(18)  = GND
  DQS4N  = M_H_DQS_DN<4>
  DQS4P  = M_H_DQS_DP<4>
  VSS(17)  = GND
  DQ(39)  = M_H_DQ<38>
  VSS(16)  = GND
  DQ(35)  = M_H_DQ<34>
  VSS(15)  = GND
  DQ(45)  = M_H_DQ<44>
  VSS(14)  = GND
  DQ(41)  = M_H_DQ<40>
  VSS(13)  = GND
  DQS5N  = M_H_DQS_DN<5>
  DQS5P  = M_H_DQS_DP<5>
  VSS(12)  = GND
  DQ(47)  = M_H_DQ<46>
  VSS(11)  = GND
  DQ(43)  = M_H_DQ<42>
  VSS(10)  = GND
  DQ(53)  = M_H_DQ<52>
  VSS(9)  = GND
  DQ(49)  = M_H_DQ<48>
  VSS(8)  = GND
  DQS6N  = M_H_DQS_DN<6>
  DQS6P  = M_H_DQS_DP<6>
  VSS(7)  = GND
  DQ(55)  = M_H_DQ<54>
  VSS(6)  = GND
  DQ(51)  = M_H_DQ<50>
  VSS(5)  = GND
  DQ(61)  = M_H_DQ<60>
  VSS(4)  = GND
  DQ(57)  = M_H_DQ<56>
  VSS(3)  = GND
  DQS7N  = M_H_DQS_DN<7>
  DQS7P  = M_H_DQS_DP<7>
  VSS(2)  = GND
  DQ(63)  = M_H_DQ<62>
  VSS(1)  = GND
  DQ(59)  = M_H_DQ<58>
  VSS(0)  = GND
  VDDSPD  = PVPP_GHJ
  SDA  = SMB_DDR_GHJ_VPP_SDA
  VPP(1)  = PVPP_GHJ
  VPP(0)  = PVPP_GHJ
  VPP(2)  = PVPP_GHJ

(kicad_pcb
	(version 20260206)
	(generator "pcbnew")
	(generator_version "10.0")
	(general
		(thickness 1.6)
		(legacy_teardrops no)
	)
	(paper "A4")
	(title_block
		(title "Wiwynn_Tioga_Pass_MB.brd")
		(comment 1 "Tioga Pass / footprint 2141 of 4770 (J1G2), pads 51-100 of 291")
	)
	(layers
		(0 "F.Cu" signal "TOP")
		(4 "In1.Cu" signal "L2GND")
		(6 "In2.Cu" signal "L3")
		(8 "In3.Cu" signal "L4GND")
		(10 "In4.Cu" signal "L5")
		(12 "In5.Cu" signal "L6GND")
		(14 "In6.Cu" signal "L7VCC")
		(16 "In7.Cu" signal "L8VCC")
		(18 "In8.Cu" signal "L9GND")
		(20 "In9.Cu" signal "L10")
		(22 "In10.Cu" signal "L11GND")
		(24 "In11.Cu" signal "L12")
		(26 "In12.Cu" signal "L13GND")
		(2 "B.Cu" signal "BOTTOM")
		(9 "F.Adhes" user "F.Adhesive")
		(11 "B.Adhes" user "B.Adhesive")
		(13 "F.Paste" user "Package Geometry/Pastemask Top")
		(15 "B.Paste" user "Package Geometry/Pastemask Bottom")
		(5 "F.SilkS" user "Ref Des/Silkscreen Top")
		(7 "B.SilkS" user "Ref Des/Silkscreen Bottom")
		(1 "F.Mask" user "Board Geometry/Soldermask Top")
		(3 "B.Mask" user "Board Geometry/Soldermask Bottom")
		(17 "Dwgs.User" user "User.Drawings")
		(19 "Cmts.User" user "User.Comments")
		(21 "Eco1.User" user "User.Eco1")
		(23 "Eco2.User" user "User.Eco2")
		(25 "Edge.Cuts" user "Board Geometry/Outline")
		(27 "Margin" user)
		(31 "F.CrtYd" user "Package Geometry/Place Bound Top")
		(29 "B.CrtYd" user "Package Geometry/Place Bound Bottom")
		(35 "F.Fab" user "Ref Des/Assembly Top")
		(33 "B.Fab" user "Ref Des/Assembly Bottom")
	)
	(footprint ""
		(layer "F.Cu")
		(at 29.699458 -5.822442 90)
		(property "Reference" "J1G2"
			(at 7.104888 34.562542 0)
			(unlocked yes)
			(layer "F.SilkS")
			(effects
				(font
					(size 0.7874 0.5842)
					(thickness 0.1524)
				)
				(justify left)
			)
		)
		(property "Value" ""
			(at 0 0 90)
			(layer "F.Fab")
			(effects
				(font
					(size 1.27 1.27)
				)
			)
		)
		(duplicate_pad_numbers_are_jumpers no)
		(pad "48" smd rect
			(at 0 39.949882 90)
			(size 1.8034 0.508)
			(layers "F.Cu" "F.Mask" "F.Paste")
			(net "GND")
		)
		(pad "49" smd rect
			(at 0 40.80002 90)
			(size 1.8034 0.508)
			(layers "F.Cu" "F.Mask" "F.Paste")
			(net "M_H_ECC<1>")
		)
		(pad "50" smd rect
			(at 0 41.649904 90)
			(size 1.8034 0.508)
			(layers "F.Cu" "F.Mask" "F.Paste")
			(net "GND")
		)
		(pad "51" smd rect
			(at 0 42.500042 90)
			(size 1.8034 0.508)
			(layers "F.Cu" "F.Mask" "F.Paste")
			(net "M_H_DQS_DP<17>")
		)
		(pad "52" smd rect
			(at 0 43.349926 90)
			(size 1.8034 0.508)
			(layers "F.Cu" "F.Mask" "F.Paste")
			(net "M_H_DQS_DN<17>")
		)
		(pad "53" smd rect
			(at 0 44.200064 90)
			(size 1.8034 0.508)
			(layers "F.Cu" "F.Mask" "F.Paste")
			(net "GND")
		)
		(pad "54" smd rect
			(at 0 45.049948 90)
			(size 1.8034 0.508)
			(layers "F.Cu" "F.Mask" "F.Paste")
			(net "M_H_ECC<7>")
		)
		(pad "55" smd rect
			(at 0 45.900086 90)
			(size 1.8034 0.508)
			(layers "F.Cu" "F.Mask" "F.Paste")
			(net "GND")
		)
		(pad "56" smd rect
			(at 0 46.74997 90)
			(size 1.8034 0.508)
			(layers "F.Cu" "F.Mask" "F.Paste")
			(net "M_H_ECC<3>")
		)
		(pad "57" smd rect
			(at 0 47.600108 90)
			(size 1.8034 0.508)
			(layers "F.Cu" "F.Mask" "F.Paste")
			(net "GND")
		)
		(pad "58" smd rect
			(at 0 48.449992 90)
			(size 1.8034 0.508)
			(layers "F.Cu" "F.Mask" "F.Paste")
			(net "M_GHJ_RST_N")
		)
		(pad "59" smd rect
			(at 0 49.299876 90)
			(size 1.8034 0.508)
			(layers "F.Cu" "F.Mask" "F.Paste")
			(net "PVDDQ_GHJ")
		)
		(pad "60" smd rect
			(at 0 50.150014 90)
			(size 1.8034 0.508)
			(layers "F.Cu" "F.Mask" "F.Paste")
			(net "M_H_CKE<0>")
		)
		(pad "61" smd rect
			(at 0 50.999898 90)
			(size 1.8034 0.508)
			(layers "F.Cu" "F.Mask" "F.Paste")
			(net "PVDDQ_GHJ")
		)
		(pad "62" smd rect
			(at 0 51.850036 90)
			(size 1.8034 0.508)
			(layers "F.Cu" "F.Mask" "F.Paste")
			(net "M_H_ACT_N")
		)
		(pad "63" smd rect
			(at 0 52.69992 90)
			(size 1.8034 0.508)
			(layers "F.Cu" "F.Mask" "F.Paste")
			(net "M_H_BG<0>")
		)
		(pad "64" smd rect
			(at 0 53.550058 90)
			(size 1.8034 0.508)
			(layers "F.Cu" "F.Mask" "F.Paste")
			(net "PVDDQ_GHJ")
		)
		(pad "65" smd rect
			(at 0 54.399942 90)
			(size 1.8034 0.508)
			(layers "F.Cu" "F.Mask" "F.Paste")
			(net "M_H_MA<12>")
		)
		(pad "66" smd rect
			(at 0 55.25008 90)
			(size 1.8034 0.508)
			(layers "F.Cu" "F.Mask" "F.Paste")
			(net "M_H_MA<9>")
		)
		(pad "67" smd rect
			(at 0 56.099964 90)
			(size 1.8034 0.508)
			(layers "F.Cu" "F.Mask" "F.Paste")
			(net "PVDDQ_GHJ")
		)
		(pad "68" smd rect
			(at 0 56.950102 90)
			(size 1.8034 0.508)
			(layers "F.Cu" "F.Mask" "F.Paste")
			(net "M_H_MA<8>")
		)
		(pad "69" smd rect
			(at 0 57.799986 90)
			(size 1.8034 0.508)
			(layers "F.Cu" "F.Mask" "F.Paste")
			(net "M_H_MA<6>")
		)
		(pad "70" smd rect
			(at 0 58.650124 90)
			(size 1.8034 0.508)
			(layers "F.Cu" "F.Mask" "F.Paste")
			(net "PVDDQ_GHJ")
		)
		(pad "71" smd rect
			(at 0 59.500008 90)
			(size 1.8034 0.508)
			(layers "F.Cu" "F.Mask" "F.Paste")
			(net "M_H_MA<3>")
		)
		(pad "72" smd rect
			(at 0 60.349892 90)
			(size 1.8034 0.508)
			(layers "F.Cu" "F.Mask" "F.Paste")
			(net "M_H_MA<1>")
		)
		(pad "73" smd rect
			(at 0 61.20003 90)
			(size 1.8034 0.508)
			(layers "F.Cu" "F.Mask" "F.Paste")
			(net "PVDDQ_GHJ")
		)
		(pad "74" smd rect
			(at 0 62.049914 90)
			(size 1.8034 0.508)
			(layers "F.Cu" "F.Mask" "F.Paste")
			(net "M_H_CLK_DP<0>")
		)
		(pad "75" smd rect
			(at 0 62.900052 90)
			(size 1.8034 0.508)
			(layers "F.Cu" "F.Mask" "F.Paste")
			(net "M_H_CLK_DN<0>")
		)
		(pad "76" smd rect
			(at 0 63.749936 90)
			(size 1.8034 0.508)
			(layers "F.Cu" "F.Mask" "F.Paste")
			(net "PVDDQ_GHJ")
		)
		(pad "77" smd rect
			(at 0 64.600074 90)
			(size 1.8034 0.508)
			(layers "F.Cu" "F.Mask" "F.Paste")
			(net "PVTT_GHJ")
		)
		(pad "78" smd rect
			(at 0 70.550024 90)
			(size 1.8034 0.508)
			(layers "F.Cu" "F.Mask" "F.Paste")
			(net "FM_DIMM_EVENT_COD_N")
		)
		(pad "79" smd rect
			(at 0 71.399908 90)
			(size 1.8034 0.508)
			(layers "F.Cu" "F.Mask" "F.Paste")
			(net "M_H_MA<0>")
		)
		(pad "80" smd rect
			(at 0 72.250046 90)
			(size 1.8034 0.508)
			(layers "F.Cu" "F.Mask" "F.Paste")
			(net "PVDDQ_GHJ")
		)
		(pad "81" smd rect
			(at 0 73.09993 90)
			(size 1.8034 0.508)
			(layers "F.Cu" "F.Mask" "F.Paste")
			(net "M_H_BA<0>")
		)
		(pad "82" smd rect
			(at 0 73.950068 90)
			(size 1.8034 0.508)
			(layers "F.Cu" "F.Mask" "F.Paste")
			(net "M_H_MA<16>")
		)
		(pad "83" smd rect
			(at 0 74.799952 90)
			(size 1.8034 0.508)
			(layers "F.Cu" "F.Mask" "F.Paste")
			(net "PVDDQ_GHJ")
		)
		(pad "84" smd rect
			(at 0 75.65009 90)
			(size 1.8034 0.508)
			(layers "F.Cu" "F.Mask" "F.Paste")
			(net "M_H_CS_N<0>")
		)
		(pad "85" smd rect
			(at 0 76.499974 90)
			(size 1.8034 0.508)
			(layers "F.Cu" "F.Mask" "F.Paste")
			(net "PVDDQ_GHJ")
		)
		(pad "86" smd rect
			(at 0 77.350112 90)
			(size 1.8034 0.508)
			(layers "F.Cu" "F.Mask" "F.Paste")
			(net "M_H_MA<15>")
		)
		(pad "87" smd rect
			(at 0 78.199996 90)
			(size 1.8034 0.508)
			(layers "F.Cu" "F.Mask" "F.Paste")
			(net "M_H_ODT<0>")
		)
		(pad "88" smd rect
			(at 0 79.04988 90)
			(size 1.8034 0.508)
			(layers "F.Cu" "F.Mask" "F.Paste")
			(net "PVDDQ_GHJ")
		)
		(pad "89" smd rect
			(at 0 79.900018 90)
			(size 1.8034 0.508)
			(layers "F.Cu" "F.Mask" "F.Paste")
			(net "M_H_CS_N<1>")
		)
		(pad "90" smd rect
			(at 0 80.749902 90)
			(size 1.8034 0.508)
			(layers "F.Cu" "F.Mask" "F.Paste")
			(net "PVDDQ_GHJ")
		)
		(pad "91" smd rect
			(at 0 81.60004 90)
			(size 1.8034 0.508)
			(layers "F.Cu" "F.Mask" "F.Paste")
			(net "M_H_ODT<1>")
		)
		(pad "92" smd rect
			(at 0 82.449924 90)
			(size 1.8034 0.508)
			(layers "F.Cu" "F.Mask" "F.Paste")
			(net "PVDDQ_GHJ")
		)
		(pad "93" smd rect
			(at 0 83.300062 90)
			(size 1.8034 0.508)
			(layers "F.Cu" "F.Mask" "F.Paste")
			(net "M_H_CS_N<2>")
		)
		(pad "94" smd rect
			(at 0 84.149946 90)
			(size 1.8034 0.508)
			(layers "F.Cu" "F.Mask" "F.Paste")
			(net "GND")
		)
		(pad "95" smd rect
			(at 0 85.000084 90)
			(size 1.8034 0.508)
			(layers "F.Cu" "F.Mask" "F.Paste")
			(net "M_H_DQ<37>")
		)
		(pad "96" smd rect
			(at 0 85.849968 90)
			(size 1.8034 0.508)
			(layers "F.Cu" "F.Mask" "F.Paste")
			(net "GND")
		)
		(pad "97" smd rect
			(at 0 86.700106 90)
			(size 1.8034 0.508)
			(layers "F.Cu" "F.Mask" "F.Paste")
			(net "M_H_DQ<33>")
		)
	)
)
